#ISCELL
  pure_quanta quanta_title_block_c *
  *
#CELL
  pure_quanta lcmxo3lf2100c5bg256c *
  page37_i1
#ISCELL
  logical_power universal_power *
  page37_i3
